(kicad_pcb
	(version 20240108)
	(generator "pcbnew")
	(generator_version "8.0")
	(general
		(thickness 1.62)
		(legacy_teardrops no)
	)
	(paper "A4")
	(title_block
		(title "Jetson Orin Baseboard")
		(date "2025-03-12")
		(rev "1.3.4")
		(company "Antmicro Ltd")
		(comment 1 "www.antmicro.com")
		(comment 9 "footprints 618-621 of 677")
	)
	(layers
		(0 "F.Cu" signal)
		(1 "In1.Cu" signal)
		(2 "In2.Cu" signal)
		(3 "In3.Cu" signal)
		(4 "In4.Cu" jumper)
		(5 "In5.Cu" signal)
		(6 "In6.Cu" signal)
		(31 "B.Cu" signal)
		(32 "B.Adhes" user "B.Adhesive")
		(33 "F.Adhes" user "F.Adhesive")
		(34 "B.Paste" user)
		(35 "F.Paste" user)
		(36 "B.SilkS" user "B.Silkscreen")
		(37 "F.SilkS" user "F.Silkscreen")
		(38 "B.Mask" user)
		(39 "F.Mask" user)
		(40 "Dwgs.User" user "User.Drawings")
		(41 "Cmts.User" user "User.Comments")
		(42 "Eco1.User" user "User.Eco1")
		(43 "Eco2.User" user "User.Eco2")
		(44 "Edge.Cuts" user)
		(45 "Margin" user)
		(46 "B.CrtYd" user "B.Courtyard")
		(47 "F.CrtYd" user "F.Courtyard")
		(48 "B.Fab" user)
		(49 "F.Fab" user)
	)
	(footprint "antmicro-footprints:R_0603_1608Metric"
		(layer "B.Cu")
		(at 119.56 99.99 -90)
		(descr "Resistor SMD 0603")
		(tags "resistor SMD 0603")
		(property "Reference" "R143"
			(at -1.44 0.66 90)
			(layer "B.SilkS")
			(effects
				(font
					(size 0.7 0.7)
					(thickness 0.15)
				)
				(justify left bottom mirror)
			)
		)
		(property "Value" "R_0R_22.4A_0603"
			(at 0 -1.6 90)
			(layer "B.Fab")
			(effects
				(font
					(size 0.7 0.7)
					(thickness 0.15)
				)
				(justify left bottom mirror)
			)
		)
		(property "Footprint" "antmicro-footprints:R_0603_1608Metric"
			(at 0 0 -90)
			(layer "F.Fab")
			(hide yes)
			(effects
				(font
					(size 1.27 1.27)
					(thickness 0.15)
				)
			)
		)
		(property "Datasheet" "https://fscdn.rohm.com/en/products/databook/datasheet/passive/resistor/chip_resistor/pmr-jpw-e.pdf"
			(at 0 0 -90)
			(layer "F.Fab")
			(hide yes)
			(effects
				(font
					(size 1.27 1.27)
					(thickness 0.15)
				)
			)
		)
		(property "Author" "Antmicro"
			(at 19.57 219.55 0)
			(layer "B.Fab")
			(hide yes)
			(effects
				(font
					(size 1 1)
					(thickness 0.15)
				)
				(justify mirror)
			)
		)
		(property "License" "Apache-2.0"
			(at 19.57 219.55 0)
			(layer "B.Fab")
			(hide yes)
			(effects
				(font
					(size 1 1)
					(thickness 0.15)
				)
				(justify mirror)
			)
		)
		(property "MPN" "PMR03EZPJ000"
			(at 19.57 219.55 0)
			(layer "B.Fab")
			(hide yes)
			(effects
				(font
					(size 1 1)
					(thickness 0.15)
				)
				(justify mirror)
			)
		)
		(property "Manufacturer" "ROHM Semiconductor"
			(at 19.57 219.55 0)
			(layer "B.Fab")
			(hide yes)
			(effects
				(font
					(size 1 1)
					(thickness 0.15)
				)
				(justify mirror)
			)
		)
		(property "Max. Curr." "22.4A"
			(at 19.57 219.55 0)
			(layer "B.Fab")
			(hide yes)
			(effects
				(font
					(size 1 1)
					(thickness 0.15)
				)
				(justify mirror)
			)
		)
		(property "Tolerance" "template_tolerance"
			(at 19.57 219.55 0)
			(layer "B.Fab")
			(hide yes)
			(effects
				(font
					(size 1 1)
					(thickness 0.15)
				)
				(justify mirror)
			)
		)
		(property "Val" "0R"
			(at 19.57 219.55 0)
			(layer "B.Fab")
			(hide yes)
			(effects
				(font
					(size 1 1)
					(thickness 0.15)
				)
				(justify mirror)
			)
		)
		(sheetname "M.2")
		(sheetfile "m-2.kicad_sch")
		(attr smd)
		(fp_line
			(start 0.15 0.4)
			(end -0.15 0.4)
			(stroke
				(width 0.15)
				(type solid)
			)
			(layer "B.SilkS")
		)
		(fp_line
			(start 0.15 -0.4)
			(end -0.15 -0.4)
			(stroke
				(width 0.15)
				(type solid)
			)
			(layer "B.SilkS")
		)
		(fp_rect
			(start -1.25 0.65)
			(end 1.25 -0.65)
			(stroke
				(width 0.05)
				(type solid)
			)
			(fill none)
			(layer "B.CrtYd")
		)
		(fp_rect
			(start -0.8 0.4)
			(end 0.8 -0.4)
			(stroke
				(width 0.15)
				(type solid)
			)
			(fill none)
			(layer "B.Fab")
		)
		(fp_text user "Author: Antmicro"
			(at -1.25 -4.9 90)
			(layer "B.Fab")
			(hide yes)
			(effects
				(font
					(size 0.7 0.7)
					(thickness 0.15)
				)
				(justify left bottom mirror)
			)
		)
		(fp_text user "${REFERENCE}"
			(at -1.25 -3.898 90)
			(layer "B.Fab")
			(hide yes)
			(effects
				(font
					(size 0.7 0.7)
					(thickness 0.15)
				)
				(justify left bottom mirror)
			)
		)
		(fp_text user "License: Apache-2.0"
			(at -1.25 -5.9 90)
			(layer "B.Fab")
			(hide yes)
			(effects
				(font
					(size 0.7 0.7)
					(thickness 0.15)
				)
				(justify left bottom mirror)
			)
		)
		(pad "1" smd roundrect
			(at -0.7 0 270)
			(size 0.8 1)
			(layers "B.Cu" "B.Paste" "B.Mask")
			(roundrect_rratio 0.2)
			(net 635 "/M.2/3V3_M2")
			(pintype "passive")
		)
		(pad "2" smd roundrect
			(at 0.7 0 270)
			(size 0.8 1)
			(layers "B.Cu" "B.Paste" "B.Mask")
			(roundrect_rratio 0.2)
			(net 87 "+3V3")
			(pintype "passive")
		)
	)
	(footprint "antmicro-footprints:LED_0603_1608Metric_G"
		(layer "B.Cu")
		(at 44.2 126.95 180)
		(descr "LED SMD 0603 Green")
		(tags "LED SMD 0603 Green")
		(property "Reference" "D3"
			(at 4.55 -1.3 0)
			(layer "B.SilkS")
			(effects
				(font
					(size 0.7 0.7)
					(thickness 0.15)
				)
				(justify left bottom mirror)
			)
		)
		(property "Value" "LED_G_0603_LTST-C190GKT"
			(at -0.001 -1.599 0)
			(layer "B.Fab")
			(effects
				(font
					(size 0.7 0.7)
					(thickness 0.15)
				)
				(justify left bottom mirror)
			)
		)
		(property "Footprint" "antmicro-footprints:LED_0603_1608Metric_G"
			(at 0 0 180)
			(layer "F.Fab")
			(hide yes)
			(effects
				(font
					(size 1.27 1.27)
					(thickness 0.15)
				)
			)
		)
		(property "Datasheet" "https://media.digikey.com/pdf/Data%20Sheets/Lite-On%20PDFs/LTST-C190GKT.pdf"
			(at 0 0 180)
			(layer "F.Fab")
			(hide yes)
			(effects
				(font
					(size 1.27 1.27)
					(thickness 0.15)
				)
			)
		)
		(property "Author" "Antmicro"
			(at 88.4 253.9 0)
			(layer "B.Fab")
			(hide yes)
			(effects
				(font
					(size 1 1)
					(thickness 0.15)
				)
				(justify mirror)
			)
		)
		(property "Color" "Green"
			(at 88.4 253.9 0)
			(layer "B.Fab")
			(hide yes)
			(effects
				(font
					(size 1 1)
					(thickness 0.15)
				)
				(justify mirror)
			)
		)
		(property "License" "Apache-2.0"
			(at 88.4 253.9 0)
			(layer "B.Fab")
			(hide yes)
			(effects
				(font
					(size 1 1)
					(thickness 0.15)
				)
				(justify mirror)
			)
		)
		(property "MPN" "LTST-C190GKT"
			(at 88.4 253.9 0)
			(layer "B.Fab")
			(hide yes)
			(effects
				(font
					(size 1 1)
					(thickness 0.15)
				)
				(justify mirror)
			)
		)
		(property "Manufacturer" "Lite-On"
			(at 88.4 253.9 0)
			(layer "B.Fab")
			(hide yes)
			(effects
				(font
					(size 1 1)
					(thickness 0.15)
				)
				(justify mirror)
			)
		)
		(sheetname "USB Debug, DP")
		(sheetfile "usb.kicad_sch")
		(attr smd)
		(fp_line
			(start 0.24 -0.001)
			(end 0.105328 -0.001008)
			(stroke
				(width 0.1)
				(type solid)
			)
			(layer "B.SilkS")
		)
		(fp_line
			(start 0.105328 0.198992)
			(end 0.105328 -0.201008)
			(stroke
				(width 0.1)
				(type solid)
			)
			(layer "B.SilkS")
		)
		(fp_line
			(start 0.105328 0.198992)
			(end -0.094672 -0.001008)
			(stroke
				(width 0.1)
				(type solid)
			)
			(layer "B.SilkS")
		)
		(fp_line
			(start -0.094672 0.198992)
			(end -0.094672 -0.201008)
			(stroke
				(width 0.1)
				(type solid)
			)
			(layer "B.SilkS")
		)
		(fp_line
			(start -0.094672 -0.001008)
			(end 0.105328 -0.201008)
			(stroke
				(width 0.1)
				(type solid)
			)
			(layer "B.SilkS")
		)
		(fp_line
			(start -0.22 0.35)
			(end 0.22 0.35)
			(stroke
				(width 0.15)
				(type solid)
			)
			(layer "B.SilkS")
		)
		(fp_line
			(start -0.22 -0.35)
			(end 0.22 -0.35)
			(stroke
				(width 0.15)
				(type solid)
			)
			(layer "B.SilkS")
		)
		(fp_line
			(start -0.24 -0.001008)
			(end -0.094672 -0.001008)
			(stroke
				(width 0.1)
				(type solid)
			)
			(layer "B.SilkS")
		)
		(fp_line
			(start -1.18 -0.321)
			(end -1.18 0.319)
			(stroke
				(width 0.15)
				(type solid)
			)
			(layer "B.SilkS")
		)
		(fp_rect
			(start 1.25 -0.65)
			(end -1.25 0.65)
			(stroke
				(width 0.05)
				(type solid)
			)
			(fill none)
			(layer "B.CrtYd")
		)
		(fp_line
			(start 0.201 0.202)
			(end 0.201 0)
			(stroke
				(width 0.15)
				(type solid)
			)
			(layer "B.Fab")
		)
		(fp_line
			(start 0.201 0)
			(end 0.599 0)
			(stroke
				(width 0.15)
				(type solid)
			)
			(layer "B.Fab")
		)
		(fp_line
			(start 0.201 0)
			(end 0.201 -0.2)
			(stroke
				(width 0.15)
				(type solid)
			)
			(layer "B.Fab")
		)
		(fp_line
			(start 0.201 -0.2)
			(end -0.101 0)
			(stroke
				(width 0.15)
				(type solid)
			)
			(layer "B.Fab")
		)
		(fp_line
			(start -0.101 0)
			(end 0.201 0.202)
			(stroke
				(width 0.15)
				(type solid)
			)
			(layer "B.Fab")
		)
		(fp_line
			(start -0.199 -0.1)
			(end -0.199 0.202)
			(stroke
				(width 0.15)
				(type solid)
			)
			(layer "B.Fab")
		)
		(fp_line
			(start -0.199 -0.1)
			(end -0.199 -0.2)
			(stroke
				(width 0.15)
				(type solid)
			)
			(layer "B.Fab")
		)
		(fp_line
			(start -0.597 0)
			(end -0.199 0)
			(stroke
				(width 0.15)
				(type solid)
			)
			(layer "B.Fab")
		)
		(fp_rect
			(start 0.848 -0.4)
			(end -0.85 0.402)
			(stroke
				(width 0.15)
				(type solid)
			)
			(fill none)
			(layer "B.Fab")
		)
		(fp_text user "Author: Antmicro"
			(at -1.4224 -4.799 0)
			(layer "B.Fab")
			(hide yes)
			(effects
				(font
					(size 0.7 0.7)
					(thickness 0.15)
				)
				(justify left bottom mirror)
			)
		)
		(fp_text user "License: Apache-2.0"
			(at -1.4224 -3.599 0)
			(layer "B.Fab")
			(hide yes)
			(effects
				(font
					(size 0.7 0.7)
					(thickness 0.15)
				)
				(justify left bottom mirror)
			)
		)
		(fp_text user "${REFERENCE}"
			(at -1.4224 -5.999 0)
			(layer "B.Fab")
			(hide yes)
			(effects
				(font
					(size 0.7 0.7)
					(thickness 0.15)
				)
				(justify left bottom mirror)
			)
		)
		(pad "1" smd roundrect
			(at -0.7 0)
			(size 0.8 1)
			(layers "B.Cu" "B.Paste" "B.Mask")
			(roundrect_rratio 0.2)
			(net 272 "/USB Debug, DP/FTDI_LED_RX")
			(pinfunction "C")
			(pintype "passive")
		)
		(pad "2" smd roundrect
			(at 0.7 0)
			(size 0.8 1)
			(layers "B.Cu" "B.Paste" "B.Mask")
			(roundrect_rratio 0.2)
			(net 143 "Net-(D3-A)")
			(pinfunction "A")
			(pintype "passive")
		)
	)
	(footprint "antmicro-footprints:DFN-6-1EP_2x2mm_P0.65mm_EP1x1.6mm"
		(layer "B.Cu")
		(at 139.53 124.82)
		(descr "6-Lead Plastic Dual Flat, No Lead Package - 2x2x0.9 mm Body")
		(tags "DFN")
		(property "Reference" "U35"
			(at 2.42 0.08 90)
			(layer "B.SilkS")
			(effects
				(font
					(size 0.7 0.7)
					(thickness 0.15)
				)
				(justify left bottom mirror)
			)
		)
		(property "Value" "AP22653_DFN"
			(at 0 -2.1 180)
			(layer "B.Fab")
			(effects
				(font
					(size 0.7 0.7)
					(thickness 0.15)
				)
				(justify left bottom mirror)
			)
		)
		(property "Footprint" "antmicro-footprints:DFN-6-1EP_2x2mm_P0.65mm_EP1x1.6mm"
			(at 0 0 0)
			(layer "F.Fab")
			(hide yes)
			(effects
				(font
					(size 1.27 1.27)
					(thickness 0.15)
				)
			)
		)
		(property "Datasheet" "https://www.mouser.com/datasheet/2/115/DIOD_S_A0010880137_1-2543666.pdf"
			(at 0 0 0)
			(layer "F.Fab")
			(hide yes)
			(effects
				(font
					(size 1.27 1.27)
					(thickness 0.15)
				)
			)
		)
		(property "Author" "Antmicro"
			(at 0 0 0)
			(layer "B.Fab")
			(hide yes)
			(effects
				(font
					(size 1 1)
					(thickness 0.15)
				)
				(justify mirror)
			)
		)
		(property "License" "Apache-2.0"
			(at 0 0 0)
			(layer "B.Fab")
			(hide yes)
			(effects
				(font
					(size 1 1)
					(thickness 0.15)
				)
				(justify mirror)
			)
		)
		(property "MPN" "AP22653FDZ-7"
			(at 0 0 0)
			(layer "B.Fab")
			(hide yes)
			(effects
				(font
					(size 1 1)
					(thickness 0.15)
				)
				(justify mirror)
			)
		)
		(property "Manufacturer" "Diodes Incorporated"
			(at 0 0 0)
			(layer "B.Fab")
			(hide yes)
			(effects
				(font
					(size 1 1)
					(thickness 0.15)
				)
				(justify mirror)
			)
		)
		(sheetname "Peripherals")
		(sheetfile "peripherals.kicad_sch")
		(attr smd)
		(fp_line
			(start -1.075 -1.1125)
			(end -1.075 -0.9375)
			(stroke
				(width 0.15)
				(type solid)
			)
			(layer "B.SilkS")
		)
		(fp_line
			(start -1.075 0.925)
			(end -1.075 1.1)
			(stroke
				(width 0.15)
				(type solid)
			)
			(layer "B.SilkS")
		)
		(fp_line
			(start 1.075 -1.1125)
			(end -1.075 -1.1125)
			(stroke
				(width 0.15)
				(type solid)
			)
			(layer "B.SilkS")
		)
		(fp_line
			(start 1.075 -1.1125)
			(end 1.075 -0.9375)
			(stroke
				(width 0.15)
				(type solid)
			)
			(layer "B.SilkS")
		)
		(fp_line
			(start 1.075 0.925)
			(end 1.075 1.1)
			(stroke
				(width 0.15)
				(type solid)
			)
			(layer "B.SilkS")
		)
		(fp_line
			(start 1.075 1.1)
			(end -1.075 1.1)
			(stroke
				(width 0.15)
				(type solid)
			)
			(layer "B.SilkS")
		)
		(fp_circle
			(center -1.325 1.04571)
			(end -1.275 1.04571)
			(stroke
				(width 0.15)
				(type solid)
			)
			(fill solid)
			(layer "B.SilkS")
		)
		(fp_rect
			(start -1.405 1.25)
			(end 1.405 -1.225)
			(stroke
				(width 0.05)
				(type solid)
			)
			(fill none)
			(layer "B.CrtYd")
		)
		(fp_line
			(start -0.5 1)
			(end -1 0.5)
			(stroke
				(width 0.15)
				(type solid)
			)
			(layer "B.Fab")
		)
		(fp_rect
			(start 1 -1)
			(end -1 1)
			(stroke
				(width 0.15)
				(type solid)
			)
			(fill none)
			(layer "B.Fab")
		)
		(fp_text user "License: Apache-2.0"
			(at -1.405 -5.799 180)
			(layer "B.Fab")
			(hide yes)
			(effects
				(font
					(size 0.7 0.7)
					(thickness 0.15)
				)
				(justify left bottom mirror)
			)
		)
		(fp_text user "${REFERENCE}"
			(at -1.405 -3.4 180)
			(layer "B.Fab")
			(hide yes)
			(effects
				(font
					(size 0.7 0.7)
					(thickness 0.15)
				)
				(justify left bottom mirror)
			)
		)
		(fp_text user "Author: Antmicro"
			(at -1.405 -4.6 180)
			(layer "B.Fab")
			(hide yes)
			(effects
				(font
					(size 0.7 0.7)
					(thickness 0.15)
				)
				(justify left bottom mirror)
			)
		)
		(pad "" smd rect
			(at 0 -0.4)
			(size 0.82 0.63)
			(layers "B.Paste")
		)
		(pad "" smd rect
			(at 0 0.402)
			(size 0.82 0.63)
			(layers "B.Paste")
		)
		(pad "1" smd rect
			(at -1.051 0.652)
			(size 0.65 0.35)
			(layers "B.Cu" "B.Paste" "B.Mask")
			(net 662 "/Peripherals/I2C_CONN_3V3")
			(pinfunction "OUT")
			(pintype "power_out")
		)
		(pad "2" smd rect
			(at -1.051 0)
			(size 0.65 0.35)
			(layers "B.Cu" "B.Paste" "B.Mask")
			(net 685 "Net-(U35-ISET)")
			(pinfunction "ISET")
			(pintype "passive")
		)
		(pad "3" smd rect
			(at -1.051 -0.65)
			(size 0.65 0.35)
			(layers "B.Cu" "B.Paste" "B.Mask")
			(net 719 "unconnected-(U35-FLG-Pad3)")
			(pinfunction "FLG")
			(pintype "output+no_connect")
		)
		(pad "4" smd rect
			(at 1.05 -0.65)
			(size 0.65 0.35)
			(layers "B.Cu" "B.Paste" "B.Mask")
			(net 658 "/Peripherals/I2C_CONN_PEN")
			(pinfunction "EN")
			(pintype "input")
		)
		(pad "5" smd rect
			(at 1.05 0)
			(size 0.65 0.35)
			(layers "B.Cu" "B.Paste" "B.Mask")
			(net 1 "GND")
			(pinfunction "GND")
			(pintype "power_in")
		)
		(pad "6" smd rect
			(at 1.05 0.652)
			(size 0.65 0.35)
			(layers "B.Cu" "B.Paste" "B.Mask")
			(net 87 "+3V3")
			(pinfunction "IN")
			(pintype "power_in")
		)
		(pad "7" smd rect
			(at 0 0)
			(size 1 1.6)
			(layers "B.Cu" "B.Mask")
			(net 1 "GND")
			(pinfunction "EP")
			(pintype "power_in")
		)
	)
	(footprint "antmicro-footprints:R_0402_1005Metric"
		(layer "B.Cu")
		(at 58.65 86.77 90)
		(descr "Resistor SMD 0402")
		(tags "resistor SMD 0402")
		(property "Reference" "R268"
			(at -1.47 -0.44 90)
			(layer "B.SilkS")
			(effects
				(font
					(size 0.7 0.7)
					(thickness 0.15)
				)
				(justify right bottom mirror)
			)
		)
		(property "Value" "R_0R_0402"
			(at 0 -1.4 90)
			(layer "B.Fab")
			(effects
				(font
					(size 0.7 0.7)
					(thickness 0.15)
				)
				(justify right bottom mirror)
			)
		)
		(property "Footprint" "antmicro-footprints:R_0402_1005Metric"
			(at 0 0 90)
			(layer "F.Fab")
			(hide yes)
			(effects
				(font
					(size 1.27 1.27)
					(thickness 0.15)
				)
			)
		)
		(property "Datasheet" "https://industrial.panasonic.com/cdbs/www-data/pdf/RDA0000/AOA0000C301.pdf"
			(at 0 0 90)
			(layer "F.Fab")
			(hide yes)
			(effects
				(font
					(size 1.27 1.27)
					(thickness 0.15)
				)
			)
		)
		(property "Author" "Antmicro"
			(at 145.36 28.18 0)
			(layer "B.Fab")
			(hide yes)
			(effects
				(font
					(size 1 1)
					(thickness 0.15)
				)
				(justify mirror)
			)
		)
		(property "Current" "1A"
			(at 145.36 28.18 0)
			(layer "B.Fab")
			(hide yes)
			(effects
				(font
					(size 1 1)
					(thickness 0.15)
				)
				(justify mirror)
			)
		)
		(property "License" "Apache-2.0"
			(at 145.36 28.18 0)
			(layer "B.Fab")
			(hide yes)
			(effects
				(font
					(size 1 1)
					(thickness 0.15)
				)
				(justify mirror)
			)
		)
		(property "MPN" "ERJ2GE0R00X"
			(at 145.36 28.18 0)
			(layer "B.Fab")
			(hide yes)
			(effects
				(font
					(size 1 1)
					(thickness 0.15)
				)
				(justify mirror)
			)
		)
		(property "Manufacturer" "Panasonic"
			(at 145.36 28.18 0)
			(layer "B.Fab")
			(hide yes)
			(effects
				(font
					(size 1 1)
					(thickness 0.15)
				)
				(justify mirror)
			)
		)
		(property "Tolerance" ""
			(at 145.36 28.18 0)
			(layer "B.Fab")
			(hide yes)
			(effects
				(font
					(size 1 1)
					(thickness 0.15)
				)
				(justify mirror)
			)
		)
		(property "Val" "0R"
			(at 145.36 28.18 0)
			(layer "B.Fab")
			(hide yes)
			(effects
				(font
					(size 1 1)
					(thickness 0.15)
				)
				(justify mirror)
			)
		)
		(sheetname "Supply")
		(sheetfile "supply.kicad_sch")
		(attr smd)
		(fp_rect
			(start -0.925 0.47)
			(end 0.925 -0.47)
			(stroke
				(width 0.05)
				(type default)
			)
			(fill none)
			(layer "B.CrtYd")
		)
		(fp_rect
			(start -0.5 0.25)
			(end 0.5 -0.25)
			(stroke
				(width 0.15)
				(type solid)
			)
			(fill none)
			(layer "B.Fab")
		)
		(fp_text user "Author: Antmicro"
			(at -0.95 -4.169 90)
			(layer "B.Fab")
			(hide yes)
			(effects
				(font
					(size 0.7 0.7)
					(thickness 0.15)
				)
				(justify right bottom mirror)
			)
		)
		(fp_text user "License: Apache-2.0"
			(at -0.95 -5.169 90)
			(layer "B.Fab")
			(hide yes)
			(effects
				(font
					(size 0.7 0.7)
					(thickness 0.15)
				)
				(justify right bottom mirror)
			)
		)
		(fp_text user "${REFERENCE}"
			(at -0.95 -3.168 90)
			(layer "B.Fab")
			(hide yes)
			(effects
				(font
					(size 0.7 0.7)
					(thickness 0.15)
				)
				(justify right bottom mirror)
			)
		)
		(pad "1" smd roundrect
			(at -0.48 0 90)
			(size 0.59 0.64)
			(layers "B.Cu" "B.Paste" "B.Mask")
			(roundrect_rratio 0.25)
			(net 86 "~{RESET}")
			(pintype "passive")
		)
		(pad "2" smd roundrect
			(at 0.48 0 90)
			(size 0.59 0.64)
			(layers "B.Cu" "B.Paste" "B.Mask")
			(roundrect_rratio 0.25)
			(net 690 "Net-(U42-EN)")
			(pintype "passive")
		)
	)
)
